(kicad_pcb
	(version 20260206)
	(generator "pcbnew")
	(generator_version "10.0")
	(general
		(thickness 1.6)
		(legacy_teardrops no)
	)
	(paper "A4")
	(title_block
		(title "04192023_DAF0TMB3IC0_F0TG_MB_C_brd_V02_OCP.brd")
		(comment 1 "Grand Teton / footprints 5798-5805 of 8354")
	)
	(layers
		(0 "F.Cu" signal "TOP")
		(4 "In1.Cu" signal "GND")
		(6 "In2.Cu" signal "IN1")
		(8 "In3.Cu" signal "GND1")
		(10 "In4.Cu" signal "IN2")
		(12 "In5.Cu" signal "GND2")
		(14 "In6.Cu" signal "IN3")
		(16 "In7.Cu" signal "GND3")
		(18 "In8.Cu" signal "VCC")
		(20 "In9.Cu" signal "VCC1")
		(22 "In10.Cu" signal "GND4")
		(24 "In11.Cu" signal "IN4")
		(26 "In12.Cu" signal "GND5")
		(28 "In13.Cu" signal "IN5")
		(30 "In14.Cu" signal "GND6")
		(32 "In15.Cu" signal "IN6")
		(34 "In16.Cu" signal "GND7")
		(2 "B.Cu" signal "BOTTOM")
		(9 "F.Adhes" user "F.Adhesive")
		(11 "B.Adhes" user "B.Adhesive")
		(13 "F.Paste" user "Package Geometry/Pastemask Top")
		(15 "B.Paste" user "Package Geometry/Pastemask Bottom")
		(5 "F.SilkS" user "Ref Des/Silkscreen Top")
		(7 "B.SilkS" user "Ref Des/Silkscreen Bottom")
		(1 "F.Mask" user "Board Geometry/Soldermask Top")
		(3 "B.Mask" user "Board Geometry/Soldermask Bottom")
		(17 "Dwgs.User" user "User.Drawings")
		(19 "Cmts.User" user "User.Comments")
		(21 "Eco1.User" user "User.Eco1")
		(23 "Eco2.User" user "User.Eco2")
		(25 "Edge.Cuts" user "Board Geometry/Outline")
		(27 "Margin" user)
		(31 "F.CrtYd" user "Package Geometry/Place Bound Top")
		(29 "B.CrtYd" user "Package Geometry/Place Bound Bottom")
		(35 "F.Fab" user "Ref Des/Assembly Top")
		(33 "B.Fab" user "Ref Des/Assembly Bottom")
	)
	(footprint ""
		(layer "B.Cu")
		(at 116.880386 -269.307564)
		(property "Reference" "C2365"
			(at 0 0 0)
			(layer "B.SilkS")
			(hide yes)
			(effects
				(font
					(size 1.27 1.27)
				)
				(justify mirror)
			)
		)
		(property "Value" ""
			(at 0 0 0)
			(layer "B.Fab")
			(effects
				(font
					(size 1.27 1.27)
				)
				(justify mirror)
			)
		)
		(duplicate_pad_numbers_are_jumpers no)
		(fp_line
			(start -0.7874 -0.4064)
			(end -0.7874 0.4064)
			(stroke
				(width 0.1524)
				(type default)
			)
			(layer "B.SilkS")
		)
		(fp_line
			(start -0.7874 0.4064)
			(end 0.7874 0.4064)
			(stroke
				(width 0.1524)
				(type default)
			)
			(layer "B.SilkS")
		)
		(fp_line
			(start 0.7874 -0.4064)
			(end -0.7874 -0.4064)
			(stroke
				(width 0.1524)
				(type default)
			)
			(layer "B.SilkS")
		)
		(fp_line
			(start 0.7874 0.4064)
			(end 0.7874 -0.4064)
			(stroke
				(width 0.1524)
				(type default)
			)
			(layer "B.SilkS")
		)
		(fp_line
			(start -0.67945 -0.3048)
			(end -0.67945 0.3048)
			(stroke
				(width 0.1)
				(type default)
			)
			(layer "B.Fab")
		)
		(fp_line
			(start -0.67945 0.3048)
			(end -0.120396 0.3048)
			(stroke
				(width 0.1)
				(type default)
			)
			(layer "B.Fab")
		)
		(fp_line
			(start -0.12065 -0.3048)
			(end -0.67945 -0.3048)
			(stroke
				(width 0.1)
				(type default)
			)
			(layer "B.Fab")
		)
		(fp_line
			(start -0.12065 -0.2794)
			(end -0.12065 -0.3048)
			(stroke
				(width 0.1)
				(type default)
			)
			(layer "B.Fab")
		)
		(fp_line
			(start -0.120396 0.2794)
			(end 0.12065 0.2794)
			(stroke
				(width 0.1)
				(type default)
			)
			(layer "B.Fab")
		)
		(fp_line
			(start -0.120396 0.3048)
			(end -0.120396 0.2794)
			(stroke
				(width 0.1)
				(type default)
			)
			(layer "B.Fab")
		)
		(fp_line
			(start 0.12065 -0.305054)
			(end 0.12065 -0.2794)
			(stroke
				(width 0.1)
				(type default)
			)
			(layer "B.Fab")
		)
		(fp_line
			(start 0.12065 -0.2794)
			(end -0.12065 -0.2794)
			(stroke
				(width 0.1)
				(type default)
			)
			(layer "B.Fab")
		)
		(fp_line
			(start 0.12065 0.2794)
			(end 0.12065 0.3048)
			(stroke
				(width 0.1)
				(type default)
			)
			(layer "B.Fab")
		)
		(fp_line
			(start 0.12065 0.3048)
			(end 0.67945 0.3048)
			(stroke
				(width 0.1)
				(type default)
			)
			(layer "B.Fab")
		)
		(fp_line
			(start 0.67945 -0.305054)
			(end 0.12065 -0.305054)
			(stroke
				(width 0.1)
				(type default)
			)
			(layer "B.Fab")
		)
		(fp_line
			(start 0.67945 0.3048)
			(end 0.67945 -0.305054)
			(stroke
				(width 0.1)
				(type default)
			)
			(layer "B.Fab")
		)
		(pad "1" smd circle
			(at 0.40005 0 180)
			(size 0 0)
			(layers "B.Cu" "B.Mask" "B.Paste")
			(net "PVDDCR_CPU1_P1")
		)
		(pad "2" smd circle
			(at -0.40005 0 180)
			(size 0 0)
			(layers "B.Cu" "B.Mask" "B.Paste")
			(net "GND")
		)
	)
	(footprint ""
		(layer "B.Cu")
		(at 365.064294 -184.48909 90)
		(property "Reference" "PC494"
			(at 5.894324 -1.181862 270)
			(unlocked yes)
			(layer "B.SilkS")
			(effects
				(font
					(size 0.7874 0.5842)
					(thickness 0.1524)
				)
				(justify left mirror)
			)
		)
		(property "Value" ""
			(at 0 0 90)
			(layer "B.Fab")
			(effects
				(font
					(size 1.27 1.27)
				)
				(justify mirror)
			)
		)
		(duplicate_pad_numbers_are_jumpers no)
		(fp_line
			(start 4.533392 -2.249932)
			(end -4.533392 -2.249932)
			(stroke
				(width 0.1524)
				(type default)
			)
			(layer "B.SilkS")
		)
		(fp_line
			(start -4.533392 -2.249932)
			(end -4.533392 2.249932)
			(stroke
				(width 0.1524)
				(type default)
			)
			(layer "B.SilkS")
		)
		(fp_line
			(start 4.533392 2.249932)
			(end 4.533392 -2.249932)
			(stroke
				(width 0.1524)
				(type default)
			)
			(layer "B.SilkS")
		)
		(fp_line
			(start -4.533392 2.249932)
			(end 4.533392 2.249932)
			(stroke
				(width 0.1524)
				(type default)
			)
			(layer "B.SilkS")
		)
		(fp_rect
			(start 4.533392 -2.326132)
			(end 5.39242 2.326132)
			(stroke
				(width 0)
				(type default)
			)
			(fill yes)
			(layer "B.SilkS")
		)
		(fp_line
			(start 3.750056 -2.249932)
			(end -3.750056 -2.249932)
			(stroke
				(width 0.1)
				(type default)
			)
			(layer "B.Fab")
		)
		(fp_line
			(start -3.750056 -2.249932)
			(end -3.750056 2.249932)
			(stroke
				(width 0.1)
				(type default)
			)
			(layer "B.Fab")
		)
		(fp_line
			(start 3.750056 2.249932)
			(end 3.750056 -2.249932)
			(stroke
				(width 0.1)
				(type default)
			)
			(layer "B.Fab")
		)
		(fp_line
			(start -3.750056 2.249932)
			(end 3.750056 2.249932)
			(stroke
				(width 0.1)
				(type default)
			)
			(layer "B.Fab")
		)
		(fp_text user "-"
			(at -4.8514 -0.14605 90)
			(unlocked yes)
			(layer "B.SilkS")
			(effects
				(font
					(size 1.905 1.4224)
					(thickness 0.1524)
				)
				(justify left mirror)
			)
		)
		(fp_text user "+"
			(at 6.322314 0.786384 0)
			(unlocked yes)
			(layer "B.SilkS")
			(effects
				(font
					(size 1.905 1.4224)
					(thickness 0.1524)
				)
				(justify left mirror)
			)
		)
		(fp_text user "-"
			(at -4.8514 -0.14605 90)
			(unlocked yes)
			(layer "B.Fab")
			(effects
				(font
					(size 1.905 1.4224)
					(thickness 0.1524)
				)
				(justify left mirror)
			)
		)
		(fp_text user "+"
			(at 6.322314 0.786384 0)
			(unlocked yes)
			(layer "B.Fab")
			(effects
				(font
					(size 1.905 1.4224)
					(thickness 0.1524)
				)
				(justify left mirror)
			)
		)
		(pad "1" smd rect
			(at 3.199892 0 270)
			(size 2.413 2.8194)
			(layers "B.Cu" "B.Mask" "B.Paste")
			(net "PVDDCR_CPU0_P0")
		)
		(pad "2" smd rect
			(at -3.199892 0 270)
			(size 2.413 2.8194)
			(layers "B.Cu" "B.Mask" "B.Paste")
			(net "GND")
		)
	)
	(footprint ""
		(layer "B.Cu")
		(at 191.160146 -192.66027)
		(property "Reference" "C536"
			(at 0 0 0)
			(layer "B.SilkS")
			(hide yes)
			(effects
				(font
					(size 1.27 1.27)
				)
				(justify mirror)
			)
		)
		(property "Value" ""
			(at 0 0 0)
			(layer "B.Fab")
			(effects
				(font
					(size 1.27 1.27)
				)
				(justify mirror)
			)
		)
		(duplicate_pad_numbers_are_jumpers no)
		(fp_line
			(start -1.524 -0.762)
			(end -1.524 0.762)
			(stroke
				(width 0.1524)
				(type default)
			)
			(layer "B.SilkS")
		)
		(fp_line
			(start -1.524 0.762)
			(end 1.524 0.762)
			(stroke
				(width 0.1524)
				(type default)
			)
			(layer "B.SilkS")
		)
		(fp_line
			(start 1.524 -0.762)
			(end -1.524 -0.762)
			(stroke
				(width 0.1524)
				(type default)
			)
			(layer "B.SilkS")
		)
		(fp_line
			(start 1.524 0.762)
			(end 1.524 -0.762)
			(stroke
				(width 0.1524)
				(type default)
			)
			(layer "B.SilkS")
		)
		(fp_line
			(start -1.1049 -0.724916)
			(end 1.1049 -0.724916)
			(stroke
				(width 0.1)
				(type default)
			)
			(layer "B.Fab")
		)
		(fp_line
			(start -1.1049 0.724916)
			(end -1.1049 -0.724916)
			(stroke
				(width 0.1)
				(type default)
			)
			(layer "B.Fab")
		)
		(fp_line
			(start 1.1049 -0.724916)
			(end 1.1049 0.724916)
			(stroke
				(width 0.1)
				(type default)
			)
			(layer "B.Fab")
		)
		(fp_line
			(start 1.1049 0.724916)
			(end -1.1049 0.724916)
			(stroke
				(width 0.1)
				(type default)
			)
			(layer "B.Fab")
		)
		(pad "1" smd rect
			(at 0.889 0)
			(size 1.016 1.27)
			(layers "B.Cu" "B.Mask" "B.Paste")
			(net "P12V_MEM_CPU1")
		)
		(pad "2" smd rect
			(at -0.889 0)
			(size 1.016 1.27)
			(layers "B.Cu" "B.Mask" "B.Paste")
			(net "GND")
		)
	)
	(footprint ""
		(layer "B.Cu")
		(at 137.352278 -384.575558)
		(property "Reference" "L9"
			(at 0 0 0)
			(layer "B.SilkS")
			(hide yes)
			(effects
				(font
					(size 1.27 1.27)
				)
				(justify mirror)
			)
		)
		(property "Value" ""
			(at 0 0 0)
			(layer "B.Fab")
			(effects
				(font
					(size 1.27 1.27)
				)
				(justify mirror)
			)
		)
		(duplicate_pad_numbers_are_jumpers no)
		(fp_line
			(start -1.63576 -0.8128)
			(end -1.63576 0.8128)
			(stroke
				(width 0.1524)
				(type default)
			)
			(layer "B.SilkS")
		)
		(fp_line
			(start -1.63576 0.8128)
			(end 1.63576 0.8128)
			(stroke
				(width 0.1524)
				(type default)
			)
			(layer "B.SilkS")
		)
		(fp_line
			(start 1.63576 -0.8128)
			(end -1.63576 -0.8128)
			(stroke
				(width 0.1524)
				(type default)
			)
			(layer "B.SilkS")
		)
		(fp_line
			(start 1.63576 -0.8128)
			(end 1.63576 0.8128)
			(stroke
				(width 0.1524)
				(type default)
			)
			(layer "B.SilkS")
		)
		(fp_line
			(start -1.560576 -0.738632)
			(end 1.56083 -0.738632)
			(stroke
				(width 0.1)
				(type default)
			)
			(layer "B.Fab")
		)
		(fp_line
			(start -1.560576 0.7366)
			(end -1.560576 -0.738632)
			(stroke
				(width 0.1)
				(type default)
			)
			(layer "B.Fab")
		)
		(fp_line
			(start -1.524 0.7366)
			(end -1.560576 0.7366)
			(stroke
				(width 0.1)
				(type default)
			)
			(layer "B.Fab")
		)
		(fp_line
			(start 1.524 0.7366)
			(end -1.524 0.7366)
			(stroke
				(width 0.1)
				(type default)
			)
			(layer "B.Fab")
		)
		(fp_line
			(start 1.56083 -0.738632)
			(end 1.56083 0.7366)
			(stroke
				(width 0.1)
				(type default)
			)
			(layer "B.Fab")
		)
		(fp_line
			(start 1.56083 0.7366)
			(end 1.524 0.7366)
			(stroke
				(width 0.1)
				(type default)
			)
			(layer "B.Fab")
		)
		(pad "1" smd rect
			(at 0.94996 0)
			(size 1.1176 1.3716)
			(layers "B.Cu" "B.Mask" "B.Paste")
			(net "P1V8_CPU1_RT_1D")
		)
		(pad "2" smd rect
			(at -0.94996 0)
			(size 1.1176 1.3716)
			(layers "B.Cu" "B.Mask" "B.Paste")
			(net "P1V8_CPU1_RT3_1A")
		)
	)
	(footprint ""
		(layer "B.Cu")
		(at 368.54892 -425.775882 90)
		(property "Reference" "R839"
			(at 0 0 90)
			(layer "B.SilkS")
			(hide yes)
			(effects
				(font
					(size 1.27 1.27)
				)
				(justify mirror)
			)
		)
		(property "Value" ""
			(at 0 0 90)
			(layer "B.Fab")
			(effects
				(font
					(size 1.27 1.27)
				)
				(justify mirror)
			)
		)
		(duplicate_pad_numbers_are_jumpers no)
		(fp_line
			(start 0.32512 -0.175006)
			(end -0.32512 -0.175006)
			(stroke
				(width 0.1)
				(type default)
			)
			(layer "B.Fab")
		)
		(fp_line
			(start -0.32512 -0.175006)
			(end -0.32512 0.175006)
			(stroke
				(width 0.1)
				(type default)
			)
			(layer "B.Fab")
		)
		(fp_line
			(start 0.32512 0.175006)
			(end 0.32512 -0.175006)
			(stroke
				(width 0.1)
				(type default)
			)
			(layer "B.Fab")
		)
		(fp_line
			(start -0.32512 0.175006)
			(end 0.32512 0.175006)
			(stroke
				(width 0.1)
				(type default)
			)
			(layer "B.Fab")
		)
		(pad "1" smd rect
			(at 0.2667 0 270)
			(size 0.3048 0.381)
			(layers "B.Cu" "B.Mask" "B.Paste")
			(net "P1V8_CPU0_RT_1D")
		)
		(pad "2" smd rect
			(at -0.2667 0 90)
			(size 0.3048 0.381)
			(layers "B.Cu" "B.Mask" "B.Paste")
			(net "SMB_RT_CPU0_P3_ROM_R_SCL")
		)
	)
	(footprint ""
		(layer "B.Cu")
		(at 64.178688 -386.766562 90)
		(property "Reference" "C285"
			(at 0 0 90)
			(layer "B.SilkS")
			(hide yes)
			(effects
				(font
					(size 1.27 1.27)
				)
				(justify mirror)
			)
		)
		(property "Value" ""
			(at 0 0 90)
			(layer "B.Fab")
			(effects
				(font
					(size 1.27 1.27)
				)
				(justify mirror)
			)
		)
		(duplicate_pad_numbers_are_jumpers no)
		(fp_line
			(start 0.299974 -0.150114)
			(end -0.299974 -0.150114)
			(stroke
				(width 0.1)
				(type default)
			)
			(layer "B.Fab")
		)
		(fp_line
			(start -0.299974 -0.150114)
			(end -0.299974 0.150114)
			(stroke
				(width 0.1)
				(type default)
			)
			(layer "B.Fab")
		)
		(fp_line
			(start 0.299974 0.150114)
			(end 0.299974 -0.150114)
			(stroke
				(width 0.1)
				(type default)
			)
			(layer "B.Fab")
		)
		(fp_line
			(start -0.299974 0.150114)
			(end 0.299974 0.150114)
			(stroke
				(width 0.1)
				(type default)
			)
			(layer "B.Fab")
		)
		(pad "1" smd rect
			(at 0.2667 0 270)
			(size 0.3048 0.381)
			(layers "B.Cu" "B.Mask" "B.Paste")
			(net "P0V9_CPU1_RT0_2A")
		)
		(pad "2" smd rect
			(at -0.2667 0 270)
			(size 0.3048 0.381)
			(layers "B.Cu" "B.Mask" "B.Paste")
			(net "GND")
		)
	)
	(footprint ""
		(layer "B.Cu")
		(at 176.543208 -127.643636 180)
		(property "Reference" "R255"
			(at 0 0 0)
			(layer "B.SilkS")
			(hide yes)
			(effects
				(font
					(size 1.27 1.27)
				)
				(justify mirror)
			)
		)
		(property "Value" ""
			(at 0 0 0)
			(layer "B.Fab")
			(effects
				(font
					(size 1.27 1.27)
				)
				(justify mirror)
			)
		)
		(duplicate_pad_numbers_are_jumpers no)
		(fp_line
			(start 0.7874 0.4064)
			(end 0.7874 -0.4064)
			(stroke
				(width 0.1524)
				(type default)
			)
			(layer "B.SilkS")
		)
		(fp_line
			(start 0.7874 -0.4064)
			(end -0.7874 -0.4064)
			(stroke
				(width 0.1524)
				(type default)
			)
			(layer "B.SilkS")
		)
		(fp_line
			(start -0.7874 0.4064)
			(end 0.7874 0.4064)
			(stroke
				(width 0.1524)
				(type default)
			)
			(layer "B.SilkS")
		)
		(fp_line
			(start -0.7874 -0.4064)
			(end -0.7874 0.4064)
			(stroke
				(width 0.1524)
				(type default)
			)
			(layer "B.SilkS")
		)
		(fp_line
			(start 0.67945 0.3048)
			(end 0.67945 -0.305054)
			(stroke
				(width 0.1)
				(type default)
			)
			(layer "B.Fab")
		)
		(fp_line
			(start 0.67945 -0.305054)
			(end 0.12065 -0.305054)
			(stroke
				(width 0.1)
				(type default)
			)
			(layer "B.Fab")
		)
		(fp_line
			(start 0.12065 0.3048)
			(end 0.67945 0.3048)
			(stroke
				(width 0.1)
				(type default)
			)
			(layer "B.Fab")
		)
		(fp_line
			(start 0.12065 0.2794)
			(end 0.12065 0.3048)
			(stroke
				(width 0.1)
				(type default)
			)
			(layer "B.Fab")
		)
		(fp_line
			(start 0.12065 -0.2794)
			(end -0.12065 -0.2794)
			(stroke
				(width 0.1)
				(type default)
			)
			(layer "B.Fab")
		)
		(fp_line
			(start 0.12065 -0.305054)
			(end 0.12065 -0.2794)
			(stroke
				(width 0.1)
				(type default)
			)
			(layer "B.Fab")
		)
		(fp_line
			(start -0.120396 0.3048)
			(end -0.120396 0.2794)
			(stroke
				(width 0.1)
				(type default)
			)
			(layer "B.Fab")
		)
		(fp_line
			(start -0.120396 0.2794)
			(end 0.12065 0.2794)
			(stroke
				(width 0.1)
				(type default)
			)
			(layer "B.Fab")
		)
		(fp_line
			(start -0.12065 -0.2794)
			(end -0.12065 -0.3048)
			(stroke
				(width 0.1)
				(type default)
			)
			(layer "B.Fab")
		)
		(fp_line
			(start -0.12065 -0.3048)
			(end -0.67945 -0.3048)
			(stroke
				(width 0.1)
				(type default)
			)
			(layer "B.Fab")
		)
		(fp_line
			(start -0.67945 0.3048)
			(end -0.120396 0.3048)
			(stroke
				(width 0.1)
				(type default)
			)
			(layer "B.Fab")
		)
		(fp_line
			(start -0.67945 -0.3048)
			(end -0.67945 0.3048)
			(stroke
				(width 0.1)
				(type default)
			)
			(layer "B.Fab")
		)
		(pad "1" smd circle
			(at 0.40005 0)
			(size 0 0)
			(layers "B.Cu" "B.Mask" "B.Paste")
			(net "RST_CPU0_PERST1_N")
		)
		(pad "2" smd circle
			(at -0.40005 0)
			(size 0 0)
			(layers "B.Cu" "B.Mask" "B.Paste")
			(net "RST_CPU0_PERST1_R_N")
		)
	)
	(footprint ""
		(layer "B.Cu")
		(at 394.335 -185.63336 90)
		(property "Reference" "PC604_1"
			(at 0 0 90)
			(layer "B.SilkS")
			(hide yes)
			(effects
				(font
					(size 1.27 1.27)
				)
				(justify mirror)
			)
		)
		(property "Value" ""
			(at 0 0 90)
			(layer "B.Fab")
			(effects
				(font
					(size 1.27 1.27)
				)
				(justify mirror)
			)
		)
		(duplicate_pad_numbers_are_jumpers no)
		(fp_line
			(start 1.524 -0.762)
			(end -1.524 -0.762)
			(stroke
				(width 0.1524)
				(type default)
			)
			(layer "B.SilkS")
		)
		(fp_line
			(start -1.524 -0.762)
			(end -1.524 0.762)
			(stroke
				(width 0.1524)
				(type default)
			)
			(layer "B.SilkS")
		)
		(fp_line
			(start 1.524 0.762)
			(end 1.524 -0.762)
			(stroke
				(width 0.1524)
				(type default)
			)
			(layer "B.SilkS")
		)
		(fp_line
			(start -1.524 0.762)
			(end 1.524 0.762)
			(stroke
				(width 0.1524)
				(type default)
			)
			(layer "B.SilkS")
		)
		(fp_line
			(start 1.1049 -0.724916)
			(end 1.1049 0.724916)
			(stroke
				(width 0.1)
				(type default)
			)
			(layer "B.Fab")
		)
		(fp_line
			(start -1.1049 -0.724916)
			(end 1.1049 -0.724916)
			(stroke
				(width 0.1)
				(type default)
			)
			(layer "B.Fab")
		)
		(fp_line
			(start 1.1049 0.724916)
			(end -1.1049 0.724916)
			(stroke
				(width 0.1)
				(type default)
			)
			(layer "B.Fab")
		)
		(fp_line
			(start -1.1049 0.724916)
			(end -1.1049 -0.724916)
			(stroke
				(width 0.1)
				(type default)
			)
			(layer "B.Fab")
		)
		(pad "1" smd rect
			(at 0.889 0 90)
			(size 1.016 1.27)
			(layers "B.Cu" "B.Mask" "B.Paste")
			(net "PVDDCR_SOC_P0")
		)
		(pad "2" smd rect
			(at -0.889 0 90)
			(size 1.016 1.27)
			(layers "B.Cu" "B.Mask" "B.Paste")
			(net "GND")
		)
	)
)
